FILE_TYPE = CONNECTIVITY;
{Allegro Design Entry HDL 17.4-2019 S026 (4007227) 1/17/2022}
"PAGE_NUMBER" = 256;
0"NC";
1"GND\g";
2"GND\g";
3"GND\g";
4"GND\g";
5"GND\g";
6"P3V3_AUX\g";
7"GND\g";
8"P3V3_AUX\g";
9"GND\g";
10"P3V3_AUX\g";
11"GND\g";
12"P3V3_AUX\g";
13"GND\g";
14"GND\g";
15"P3V3_AUX\g";
16"P3V3_AUX\g";
17"P3V3_AUX\g";
18"GND\g";
19"P3V3_AUX\g";
20"GND\g";
21"GND\g";
22"P3V3_AUX\g";
23"P3V3_AUX\g";
24"GND\g";
25"RST_SWB_BIC_BUF_N";
26"FM_GPU_PWR_EN_R1";
27"UART_BMC_BIC_BUF_RX";
28"P3V3_AUX\g";
29"P3V3_AUX\g";
30"P3V3_AUX\g";
31"FM_UART_EN";
32"UART_BMC_BIC_R_RX";
33"UART_BMC_BIC_R_BUF_RX";
34"RST_SWB_BIC_R_N";
35"BMC_MONITER_R";
36"UART_BMC_BIC_RX";
37"FM_PDB_BUF_EN_R1";
38"GPU_FPGA_RST_R_N";
39"GPU_FPGA_RST_R1_BUF_N";
40"BMC_MONITER_BUF_R";
41"BMC_MONITER_BUF";
42"FM_GPU_PWR_EN_R";
43"GPU_FPGA_RST_R_BUF_N";
44"FM_GPU_PWR_EN_R_BUF";
45"RST_SWB_BIC_BUF_R_N";
%"Q_RES"
"2","(2525,2700)","0","pure_quanta","I121";
;
LOCATION"R2926"
$SEC"1"
CDS_SEC"1"
TOLERANCE"5%"
WATTAGE"1/16W"
VALUE"4.7K"
MATERIAL"CHIP"
PACK_TYPE"0402LF"
PART_NUMBER"CS24702JB10"
CDS_LIB"pure_quanta";
"A"
$PN"1"40;
"B"
$PN"2"1;
%"UNIVERSAL_GND"
"1","(2525,2475)","0","pure_quanta_power","I122";
;
HDL_POWER"GND"
CDS_LIB"pure_quanta_power";
"A"1;
%"UNIVERSAL_GND"
"1","(2625,1350)","0","pure_quanta_power","I125";
;
HDL_POWER"GND"
CDS_LIB"pure_quanta_power";
"A"2;
%"74LVC2G17GW"
"1","(1475,50)","0","pure_quanta","I127";
;
LOCATION"U196"
$SEC"1"
CDS_SEC"1"
VALUE"74LVC2G17GW"
MATERIAL"IC"
PART_TYPE"SMLF"
PART_NUMBER"AL2G0017005"
CDS_LIB"pure_quanta"
NEEDS_NO_SIZE"TRUE"
CDS_LMAN_SYM_OUTLINE"-225,275,225,-275";
"B0"
$PN"6"26;
"A1"
$PN"3"38;
"A0"
$PN"1"42;
"GND"
$PN"2"5;
"B1"
$PN"4"39;
"VCC"
$PN"5"30;
%"UNIVERSAL_GND"
"1","(2625,100)","0","pure_quanta_power","I132";
;
HDL_POWER"GND"
CDS_LIB"pure_quanta_power";
"A"3;
%"UNIVERSAL_POWER"
"1","(1625,1300)","0","pure_quanta_power","I139";
;
HDL_POWER"P3V3_AUX"
CDS_LIB"pure_quanta_power";
"A"30;
%"Q_CAP"
"1","(1625,975)","0","pure_quanta","I140";
;
LOCATION"C1770"
$SEC"1"
CDS_SEC"1"
VALUE"0.1UF"
MATERIAL"X7R"
TOLERANCE"10%"
VOLTAGE"25V"
PACK_TYPE"0402"
PART_NUMBER"CH4104K1B00"
CDS_LIB"pure_quanta";
"B"
$PN"2"4;
"A"
$PN"1"30;
%"UNIVERSAL_GND"
"1","(1625,750)","0","pure_quanta_power","I141";
;
HDL_POWER"GND"
CDS_LIB"pure_quanta_power";
"A"4;
%"UNIVERSAL_GND"
"1","(1500,-550)","0","pure_quanta_power","I142";
;
HDL_POWER"GND"
CDS_LIB"pure_quanta_power";
"A"5;
%"Q_RES"
"2","(2575,850)","0","pure_quanta","I147";
;
LOCATION"R2912"
$SEC"1"
CDS_SEC"1"
PACK_TYPE"0402LF"
MATERIAL"EMPTY"
WATTAGE"1/16W"
VALUE"4.7K"
TOLERANCE"5%"
PART_NUMBER"CS24702JB10"
CDS_LIB"pure_quanta";
"A"
$PN"1"6;
"B"
$PN"2"26;
%"UNIVERSAL_POWER"
"1","(2575,1100)","0","pure_quanta_power","I148";
;
HDL_POWER"P3V3_AUX"
CDS_LIB"pure_quanta_power";
"A"6;
%"Q_RES"
"2","(2600,2050)","0","pure_quanta","I153";
;
LOCATION"R2911"
$SEC"1"
CDS_SEC"1"
WATTAGE"1/16W"
PACK_TYPE"0402LF"
MATERIAL"EMPTY"
TOLERANCE"5%"
VALUE"4.7K"
PART_NUMBER"CS24702JB10"
CDS_LIB"pure_quanta";
"A"
$PN"1"23;
"B"
$PN"2"45;
%"Q_RES"
"1","(2850,3000)","0","pure_quanta","I154";
;
LOCATION"R2917"
$SEC"1"
CDS_SEC"1"
PACK_TYPE"0402LF"
MATERIAL"CHIP"
VALUE"49.9"
PART_NUMBER"CS04992FB07"
WATTAGE"1/16W"
TOLERANCE"1%"
CDS_LIB"pure_quanta";
"B"
$PN"2"41;
"A"
$PN"1"40;
%"Q_RES"
"1","(2925,1875)","0","pure_quanta","I155";
;
LOCATION"R2924"
$SEC"1"
CDS_SEC"1"
VALUE"49.9"
PACK_TYPE"0402LF"
MATERIAL"CHIP"
PART_NUMBER"CS04992FB07"
WATTAGE"1/16W"
TOLERANCE"1%"
CDS_LIB"pure_quanta";
"B"
$PN"2"25;
"A"
$PN"1"45;
%"Q_RES"
"1","(2825,600)","0","pure_quanta","I156";
;
LOCATION"R2925"
$SEC"1"
CDS_SEC"1"
VALUE"49.9"
MATERIAL"CHIP"
PACK_TYPE"0402LF"
PART_NUMBER"CS04992FB07"
TOLERANCE"1%"
WATTAGE"1/16W"
CDS_LIB"pure_quanta";
"B"
$PN"2"44;
"A"
$PN"1"26;
%"UNIVERSAL_GND"
"1","(-50,225)","0","pure_quanta_power","I159";
;
HDL_POWER"GND"
CDS_LIB"pure_quanta_power";
"A"7;
%"Q_RES"
"2","(-50,400)","0","pure_quanta","I160";
;
LOCATION"R2937"
$SEC"1"
CDS_SEC"1"
WATTAGE"1/16W"
VALUE"4.7K"
PACK_TYPE"0402LF"
MATERIAL"CHIP"
TOLERANCE"5%"
PART_NUMBER"CS24702JB10"
CDS_LIB"pure_quanta";
"A"
$PN"1"42;
"B"
$PN"2"7;
%"UNIVERSAL_POWER"
"1","(-75,1125)","0","pure_quanta_power","I161";
;
HDL_POWER"P3V3_AUX"
CDS_LIB"pure_quanta_power";
"A"8;
%"Q_RES"
"2","(-75,875)","0","pure_quanta","I162";
;
LOCATION"R2936"
$SEC"1"
CDS_SEC"1"
WATTAGE"1/16W"
MATERIAL"EMPTY"
VALUE"100K"
TOLERANCE"1%"
PACK_TYPE"0402LF"
PART_NUMBER"CS41002FB09"
CDS_LIB"pure_quanta";
"A"
$PN"1"8;
"B"
$PN"2"42;
%"UNIVERSAL_POWER"
"1","(2225,-1100)","0","pure_quanta_power","I165";
;
HDL_POWER"P3V3_AUX"
CDS_LIB"pure_quanta_power";
"A"29;
%"Q_CAP"
"1","(2225,-1425)","0","pure_quanta","I166";
;
LOCATION"C1803"
$SEC"1"
CDS_SEC"1"
MATERIAL"X7R"
VALUE"0.1UF"
VOLTAGE"25V"
TOLERANCE"10%"
PACK_TYPE"0402"
PART_NUMBER"CH4104K1B00"
CDS_LIB"pure_quanta";
"B"
$PN"2"9;
"A"
$PN"1"29;
%"UNIVERSAL_GND"
"1","(2225,-1650)","0","pure_quanta_power","I167";
;
HDL_POWER"GND"
CDS_LIB"pure_quanta_power";
"A"9;
%"Q_RES"
"1","(975,-1900)","0","pure_quanta","I170";
;
LOCATION"R3033"
$SEC"1"
CDS_SEC"1"
PACK_TYPE"0402LF"
VALUE"0"
MATERIAL"CHIP"
PART_NUMBER"CS00002JB13"
WATTAGE"1/16W"
TOLERANCE"5%"
CDS_LIB"pure_quanta";
"B"
$PN"2"32;
"A"
$PN"1"36;
%"Q_RES"
"1","(975,-2000)","0","pure_quanta","I171";
;
LOCATION"R3063"
$SEC"1"
CDS_SEC"1"
MATERIAL"CHIP"
PACK_TYPE"0402LF"
VALUE"0"
PART_NUMBER"CS00002JB13"
TOLERANCE"5%"
WATTAGE"1/16W"
CDS_LIB"pure_quanta";
"B"
$PN"2"31;
"A"
$PN"1"37;
%"UNIVERSAL_POWER"
"1","(0,0)","0","pure_quanta_power","I174";
;
HDL_POWER"P3V3_AUX"
CDS_LIB"pure_quanta_power";
"A"10;
%"UNIVERSAL_GND"
"1","(2650,-1025)","0","pure_quanta_power","I178";
;
HDL_POWER"GND"
CDS_LIB"pure_quanta_power";
"A"11;
%"Q_RES"
"1","(2900,-525)","0","pure_quanta","I181";
;
LOCATION"R3315"
$SEC"1"
CDS_SEC"1"
PACK_TYPE"0402LF"
VALUE"33.2"
MATERIAL"CHIP"
PART_NUMBER"CS03322FB03"
CDS_LIB"pure_quanta"
WATTAGE"1/16W"
TOLERANCE"1%";
"B"
$PN"2"43;
"A"
$PN"1"39;
%"UNIVERSAL_POWER"
"1","(2650,-75)","0","pure_quanta_power","I183";
;
HDL_POWER"P3V3_AUX"
CDS_LIB"pure_quanta_power";
"A"12;
%"UNIVERSAL_GND"
"1","(25,-900)","0","pure_quanta_power","I184";
;
HDL_POWER"GND"
CDS_LIB"pure_quanta_power";
"A"13;
%"Q_RES"
"2","(2650,-325)","0","pure_quanta","I190";
;
LOCATION"R3317"
$SEC"1"
CDS_SEC"1"
TOLERANCE"5%"
VALUE"4.7K"
WATTAGE"1/16W"
MATERIAL"EMPTY"
PACK_TYPE"0402LF"
PART_NUMBER"CS24702JB10"
CDS_LIB"pure_quanta";
"A"
$PN"1"12;
"B"
$PN"2"39;
%"Q_RES"
"2","(2650,-800)","0","pure_quanta","I191";
;
LOCATION"R3509"
$SEC"1"
CDS_SEC"1"
PACK_TYPE"0402LF"
TOLERANCE"1%"
VALUE"10K"
WATTAGE"1/16W"
MATERIAL"CHIP"
PART_NUMBER"CS31002FB08"
CDS_LIB"pure_quanta";
"A"
$PN"1"39;
"B"
$PN"2"11;
%"Q_RES"
"2","(25,-725)","0","pure_quanta","I192";
;
LOCATION"R3507"
$SEC"1"
CDS_SEC"1"
WATTAGE"1/16W"
TOLERANCE"1%"
MATERIAL"CHIP"
VALUE"10K"
PACK_TYPE"0402LF"
PART_NUMBER"CS31002FB08"
CDS_LIB"pure_quanta";
"A"
$PN"1"38;
"B"
$PN"2"13;
%"Q_RES"
"2","(0,-250)","0","pure_quanta","I193";
;
LOCATION"R3506"
$SEC"1"
CDS_SEC"1"
MATERIAL"EMPTY"
VALUE"4.7K"
PACK_TYPE"0402LF"
TOLERANCE"5%"
WATTAGE"1/16W"
PART_NUMBER"CS24702JB10"
CDS_LIB"pure_quanta";
"A"
$PN"1"10;
"B"
$PN"2"38;
%"Q_RES"
"2","(2625,325)","0","pure_quanta","I194";
;
LOCATION"R3508"
$SEC"1"
CDS_SEC"1"
VALUE"54.9K"
TOLERANCE"1%"
PACK_TYPE"0402LF"
MATERIAL"CHIP"
WATTAGE"1/16W"
PART_NUMBER"CS35492FB03"
CDS_LIB"pure_quanta";
"A"
$PN"1"26;
"B"
$PN"2"3;
%"74LVC1G126SE7"
"1","(2000,-1950)","0","pure_quanta","I195";
;
LOCATION"U204"
$SEC"1"
CDS_SEC"1"
PART_TYPE"SMLF"
MATERIAL"IC"
VALUE"74LVC1G126SE-7"
PART_NUMBER"AL1G0126009"
NEEDS_NO_SIZE"TRUE"
CDS_LMAN_SYM_OUTLINE"-100,100,100,-100"
CDS_LIB"pure_quanta";
"OE"
$PN"1"31;
"GND"
$PN"3"14;
"VCC"
$PN"5"29;
"Y"
$PN"4"33;
"A"
$PN"2"32;
%"UNIVERSAL_GND"
"1","(2000,-2350)","0","pure_quanta_power","I196";
;
HDL_POWER"GND"
CDS_LIB"pure_quanta_power";
"A"14;
%"Q_RES"
"1","(3200,-1950)","0","pure_quanta","I197";
;
LOCATION"R3036"
$SEC"1"
CDS_SEC"1"
MATERIAL"CHIP"
VALUE"33.2"
PACK_TYPE"0402LF"
PART_NUMBER"CS03322FB03"
CDS_LIB"pure_quanta"
TOLERANCE"1%"
WATTAGE"1/16W";
"B"
$PN"2"27;
"A"
$PN"1"33;
%"Q_RES"
"2","(0,2150)","0","pure_quanta","I198";
;
LOCATION"R2909"
$SEC"1"
CDS_SEC"1"
VALUE"4.7K"
WATTAGE"1/16W"
TOLERANCE"5%"
MATERIAL"CHIP"
PACK_TYPE"0402LF"
PART_NUMBER"CS24702JB10"
CDS_LIB"pure_quanta";
"A"
$PN"1"19;
"B"
$PN"2"34;
%"UNIVERSAL_POWER"
"1","(650,-1250)","0","pure_quanta_power","I199";
;
HDL_POWER"P3V3_AUX"
CDS_LIB"pure_quanta_power";
"A"15;
%"Q_RES"
"2","(650,-1575)","0","pure_quanta","I200";
;
LOCATION"R4515"
$SEC"1"
CDS_SEC"1"
WATTAGE"1/16W"
MATERIAL"CHIP"
TOLERANCE"1%"
PACK_TYPE"0402LF"
VALUE"100K"
PART_NUMBER"CS41002FB09"
CDS_LIB"pure_quanta";
"A"
$PN"1"15;
"B"
$PN"2"36;
%"UNIVERSAL_POWER"
"1","(2950,-1300)","0","pure_quanta_power","I201";
;
HDL_POWER"P3V3_AUX"
CDS_LIB"pure_quanta_power";
"A"16;
%"Q_RES"
"2","(2625,1575)","0","pure_quanta","I203";
;
LOCATION"R2927"
$SEC"1"
CDS_SEC"1"
TOLERANCE"1%"
VALUE"100K"
PACK_TYPE"0402LF"
WATTAGE"1/16W"
MATERIAL"CHIP"
PART_NUMBER"CS41002FB09"
CDS_LIB"pure_quanta";
"A"
$PN"1"45;
"B"
$PN"2"2;
%"Q_RES"
"2","(2950,-1625)","0","pure_quanta","I204";
;
LOCATION"R4173"
$SEC"1"
CDS_SEC"1"
TOLERANCE"1%"
WATTAGE"1/16W"
VALUE"100K"
PACK_TYPE"0402LF"
MATERIAL"EMPTY"
PART_NUMBER"CS41002FB09"
CDS_LIB"pure_quanta";
"A"
$PN"1"16;
"B"
$PN"2"33;
%"74LVC2G17GW"
"1","(1475,2450)","0","pure_quanta","I65";
;
LOCATION"U195"
$SEC"1"
CDS_SEC"1"
PART_TYPE"SMLF"
VALUE"74LVC2G17GW"
MATERIAL"IC"
PART_NUMBER"AL2G0017005"
CDS_LIB"pure_quanta"
NEEDS_NO_SIZE"TRUE"
CDS_LMAN_SYM_OUTLINE"-225,275,225,-275";
"B0"
$PN"6"40;
"A1"
$PN"3"34;
"A0"
$PN"1"35;
"GND"
$PN"2"21;
"B1"
$PN"4"45;
"VCC"
$PN"5"28;
%"UNIVERSAL_POWER"
"1","(0,3525)","0","pure_quanta_power","I67";
;
HDL_POWER"P3V3_AUX"
CDS_LIB"pure_quanta_power";
"A"17;
%"Q_RES"
"2","(0,3275)","0","pure_quanta","I68";
;
LOCATION"R2815"
$SEC"1"
CDS_SEC"1"
VALUE"100K"
PACK_TYPE"0402LF"
MATERIAL"EMPTY"
WATTAGE"1/16W"
TOLERANCE"1%"
PART_NUMBER"CS41002FB09"
CDS_LIB"pure_quanta";
"A"
$PN"1"17;
"B"
$PN"2"35;
%"UNIVERSAL_GND"
"1","(25,2600)","0","pure_quanta_power","I69";
;
HDL_POWER"GND"
CDS_LIB"pure_quanta_power";
"A"18;
%"UNIVERSAL_POWER"
"1","(0,2400)","0","pure_quanta_power","I71";
;
HDL_POWER"P3V3_AUX"
CDS_LIB"pure_quanta_power";
"A"19;
%"UNIVERSAL_GND"
"1","(25,1500)","0","pure_quanta_power","I74";
;
HDL_POWER"GND"
CDS_LIB"pure_quanta_power";
"A"20;
%"UNIVERSAL_GND"
"1","(1500,1850)","0","pure_quanta_power","I76";
;
HDL_POWER"GND"
CDS_LIB"pure_quanta_power";
"A"21;
%"Q_RES"
"2","(2500,3225)","0","pure_quanta","I78";
;
LOCATION"R2820"
$SEC"1"
CDS_SEC"1"
VALUE"4.7K"
MATERIAL"EMPTY"
WATTAGE"1/16W"
TOLERANCE"5%"
PACK_TYPE"0402LF"
PART_NUMBER"CS24702JB10"
CDS_LIB"pure_quanta";
"A"
$PN"1"22;
"B"
$PN"2"40;
%"UNIVERSAL_POWER"
"1","(2500,3475)","0","pure_quanta_power","I80";
;
HDL_POWER"P3V3_AUX"
CDS_LIB"pure_quanta_power";
"A"22;
%"UNIVERSAL_POWER"
"1","(2600,2300)","0","pure_quanta_power","I83";
;
HDL_POWER"P3V3_AUX"
CDS_LIB"pure_quanta_power";
"A"23;
%"UNIVERSAL_POWER"
"1","(1625,3700)","0","pure_quanta_power","I87";
;
HDL_POWER"P3V3_AUX"
CDS_LIB"pure_quanta_power";
"A"28;
%"UNIVERSAL_GND"
"1","(1625,3150)","0","pure_quanta_power","I88";
;
HDL_POWER"GND"
CDS_LIB"pure_quanta_power";
"A"24;
%"Q_CAP"
"1","(1625,3375)","0","pure_quanta","I89";
;
LOCATION"C1769"
$SEC"1"
CDS_SEC"1"
PACK_TYPE"0402"
MATERIAL"X7R"
TOLERANCE"10%"
VOLTAGE"25V"
VALUE"0.1UF"
PART_NUMBER"CH4104K1B00"
CDS_LIB"pure_quanta";
"B"
$PN"2"24;
"A"
$PN"1"28;
%"Q_RES"
"2","(25,2800)","0","pure_quanta","I92";
;
LOCATION"R2915"
$SEC"1"
CDS_SEC"1"
PACK_TYPE"0402LF"
MATERIAL"CHIP"
WATTAGE"1/16W"
TOLERANCE"5%"
VALUE"4.7K"
PART_NUMBER"CS24702JB10"
CDS_LIB"pure_quanta";
"A"
$PN"1"35;
"B"
$PN"2"18;
%"Q_RES"
"2","(25,1675)","0","pure_quanta","I93";
;
LOCATION"R2916"
$SEC"1"
CDS_SEC"1"
PACK_TYPE"0402LF"
VALUE"4.7K"
WATTAGE"1/16W"
MATERIAL"EMPTY"
TOLERANCE"5%"
PART_NUMBER"CS24702JB10"
CDS_LIB"pure_quanta";
"A"
$PN"1"34;
"B"
$PN"2"20;
END.
